(kicad_pcb
	(version 20260206)
	(generator "pcbnew")
	(generator_version "10.0")
	(general
		(thickness 1.6)
		(legacy_teardrops no)
	)
	(paper "A4")
	(title_block
		(title "Wiwynn_Tioga_Pass_MB.brd")
		(comment 1 "Tioga Pass / footprints 4297-4304 of 4770")
	)
	(layers
		(0 "F.Cu" signal "TOP")
		(4 "In1.Cu" signal "L2GND")
		(6 "In2.Cu" signal "L3")
		(8 "In3.Cu" signal "L4GND")
		(10 "In4.Cu" signal "L5")
		(12 "In5.Cu" signal "L6GND")
		(14 "In6.Cu" signal "L7VCC")
		(16 "In7.Cu" signal "L8VCC")
		(18 "In8.Cu" signal "L9GND")
		(20 "In9.Cu" signal "L10")
		(22 "In10.Cu" signal "L11GND")
		(24 "In11.Cu" signal "L12")
		(26 "In12.Cu" signal "L13GND")
		(2 "B.Cu" signal "BOTTOM")
		(9 "F.Adhes" user "F.Adhesive")
		(11 "B.Adhes" user "B.Adhesive")
		(13 "F.Paste" user "Package Geometry/Pastemask Top")
		(15 "B.Paste" user "Package Geometry/Pastemask Bottom")
		(5 "F.SilkS" user "Ref Des/Silkscreen Top")
		(7 "B.SilkS" user "Ref Des/Silkscreen Bottom")
		(1 "F.Mask" user "Board Geometry/Soldermask Top")
		(3 "B.Mask" user "Board Geometry/Soldermask Bottom")
		(17 "Dwgs.User" user "User.Drawings")
		(19 "Cmts.User" user "User.Comments")
		(21 "Eco1.User" user "User.Eco1")
		(23 "Eco2.User" user "User.Eco2")
		(25 "Edge.Cuts" user "Board Geometry/Outline")
		(27 "Margin" user)
		(31 "F.CrtYd" user "Package Geometry/Place Bound Top")
		(29 "B.CrtYd" user "Package Geometry/Place Bound Bottom")
		(35 "F.Fab" user "Ref Des/Assembly Top")
		(33 "B.Fab" user "Ref Des/Assembly Bottom")
	)
	(footprint ""
		(layer "B.Cu")
		(at 455.549 -4.2164 90)
		(property "Reference" "R1U49"
			(at 0 0 90)
			(layer "B.SilkS")
			(hide yes)
			(effects
				(font
					(size 1.27 1.27)
				)
				(justify mirror)
			)
		)
		(property "Value" ""
			(at 0 0 90)
			(layer "B.Fab")
			(effects
				(font
					(size 1.27 1.27)
				)
				(justify mirror)
			)
		)
		(duplicate_pad_numbers_are_jumpers no)
		(fp_poly
			(pts
				(xy 0.2794 -0.1016) (xy -0.2794 -0.1016) (xy -0.2794 0.9906) (xy 0.2794 0.9906)
			)
			(stroke
				(width 0)
				(type default)
			)
			(fill no)
			(layer "B.CrtYd")
		)
		(fp_line
			(start 0.2794 -0.1016)
			(end 0.2794 0.9906)
			(stroke
				(width 0.1)
				(type default)
			)
			(layer "B.Fab")
		)
		(fp_line
			(start -0.2794 -0.1016)
			(end 0.2794 -0.1016)
			(stroke
				(width 0.1)
				(type default)
			)
			(layer "B.Fab")
		)
		(fp_line
			(start 0.2794 0.9906)
			(end -0.2794 0.9906)
			(stroke
				(width 0.1)
				(type default)
			)
			(layer "B.Fab")
		)
		(fp_line
			(start -0.2794 0.9906)
			(end -0.2794 -0.1016)
			(stroke
				(width 0.1)
				(type default)
			)
			(layer "B.Fab")
		)
		(pad "1" smd rect
			(at 0 0 270)
			(size 0.508 0.508)
			(layers "B.Cu" "B.Mask" "B.Paste")
			(net "P3V3_STBY")
		)
		(pad "2" smd rect
			(at 0 0.889 270)
			(size 0.508 0.508)
			(layers "B.Cu" "B.Mask" "B.Paste")
			(net "FM_BATTERY_SENSE_EN")
		)
		(zone
			(layer "B.Cu")
			(hatch none 0.5)
			(connect_pads
				(clearance 0)
			)
			(min_thickness 0.25)
			(keepout
				(tracks allowed)
				(vias not_allowed)
				(pads allowed)
				(copperpour not_allowed)
				(footprints allowed)
			)
			(placement
				(enabled no)
				(sheetname "")
			)
			(fill
				(thermal_gap 0.5)
				(thermal_bridge_width 0.5)
				(island_removal_mode 0)
			)
			(polygon
				(pts
					(xy 455.803 -4.4704) (xy 455.803 -3.9624) (xy 456.184 -3.9624) (xy 456.184 -4.4704)
				)
			)
		)
		(zone
			(layer "B.Cu")
			(hatch none 0.5)
			(connect_pads
				(clearance 0)
			)
			(min_thickness 0.25)
			(keepout
				(tracks not_allowed)
				(vias allowed)
				(pads allowed)
				(copperpour not_allowed)
				(footprints allowed)
			)
			(placement
				(enabled no)
				(sheetname "")
			)
			(fill
				(thermal_gap 0.5)
				(thermal_bridge_width 0.5)
				(island_removal_mode 0)
			)
			(polygon
				(pts
					(xy 456.184 -4.4704) (xy 456.184 -3.9624) (xy 455.803 -3.9624) (xy 455.803 -4.4704)
				)
			)
		)
	)
	(footprint ""
		(layer "B.Cu")
		(at 276.0472 -29.337 -90)
		(property "Reference" "SH4U2"
			(at 0 0 90)
			(layer "B.SilkS")
			(hide yes)
			(effects
				(font
					(size 1.27 1.27)
				)
				(justify mirror)
			)
		)
		(property "Value" ""
			(at 0 0 90)
			(layer "B.Fab")
			(effects
				(font
					(size 1.27 1.27)
				)
				(justify mirror)
			)
		)
		(duplicate_pad_numbers_are_jumpers no)
		(fp_poly
			(pts
				(xy 0.1651 -0.0508) (xy 0.1651 0.5842) (xy -0.1651 0.5842) (xy -0.1651 -0.0508)
			)
			(stroke
				(width 0)
				(type default)
			)
			(fill no)
			(layer "B.CrtYd")
		)
		(fp_line
			(start -0.1651 0.5842)
			(end 0.1651 0.5842)
			(stroke
				(width 0.1)
				(type default)
			)
			(layer "B.Fab")
		)
		(fp_line
			(start 0.1651 0.5842)
			(end 0.1651 -0.0508)
			(stroke
				(width 0.1)
				(type default)
			)
			(layer "B.Fab")
		)
		(fp_line
			(start -0.1651 -0.0508)
			(end -0.1651 0.5842)
			(stroke
				(width 0.1)
				(type default)
			)
			(layer "B.Fab")
		)
		(fp_line
			(start 0.1651 -0.0508)
			(end -0.1651 -0.0508)
			(stroke
				(width 0.1)
				(type default)
			)
			(layer "B.Fab")
		)
		(pad "1" smd custom
			(at 0 0 270)
			(size 0.0762 0.0762)
			(layers "B.Cu" "B.Mask" "B.Paste")
			(net "VSENSE_PVDDQ_ABC_P")
			(options
				(clearance outline)
				(anchor circle)
			)
			(primitives
				(gr_poly
					(pts
						(arc
							(start -0.1524 0.10795)
							(mid -0.098518 0.130268)
							(end -0.0762 0.18415)
						)
						(xy -0.0762 0.22225) (xy 0.0762 0.22225)
						(arc
							(start 0.0762 0.18415)
							(mid 0.098518 0.130268)
							(end 0.1524 0.10795)
						)
						(xy 0.1524 -0.22225) (xy -0.1524 -0.22225)
					)
					(width 0)
					(fill yes)
				)
			)
		)
		(pad "2" smd custom
			(at 0 0.5334 90)
			(size 0.0762 0.0762)
			(layers "B.Cu" "B.Mask" "B.Paste")
			(net "PVDDQ_ABC")
			(options
				(clearance outline)
				(anchor circle)
			)
			(primitives
				(gr_poly
					(pts
						(arc
							(start -0.1524 0.10795)
							(mid -0.098518 0.130268)
							(end -0.0762 0.18415)
						)
						(xy -0.0762 0.22225) (xy 0.0762 0.22225)
						(arc
							(start 0.0762 0.18415)
							(mid 0.098518 0.130268)
							(end 0.1524 0.10795)
						)
						(xy 0.1524 -0.22225) (xy -0.1524 -0.22225)
					)
					(width 0)
					(fill yes)
				)
			)
		)
	)
	(footprint ""
		(layer "B.Cu")
		(at 264.416286 -79.60614 180)
		(property "Reference" "C5P16"
			(at 0 0 0)
			(layer "B.SilkS")
			(hide yes)
			(effects
				(font
					(size 1.27 1.27)
				)
				(justify mirror)
			)
		)
		(property "Value" ""
			(at 0 0 0)
			(layer "B.Fab")
			(effects
				(font
					(size 1.27 1.27)
				)
				(justify mirror)
			)
		)
		(duplicate_pad_numbers_are_jumpers no)
		(fp_poly
			(pts
				(xy 0.7239 -0.2159) (xy -0.7239 -0.2159) (xy -0.7239 1.9939) (xy 0.7239 1.9939)
			)
			(stroke
				(width 0)
				(type default)
			)
			(fill no)
			(layer "B.CrtYd")
		)
		(fp_line
			(start 0.7239 1.9939)
			(end -0.7239 1.9939)
			(stroke
				(width 0.1)
				(type default)
			)
			(layer "B.Fab")
		)
		(fp_line
			(start 0.7239 -0.2159)
			(end 0.7239 1.9939)
			(stroke
				(width 0.1)
				(type default)
			)
			(layer "B.Fab")
		)
		(fp_line
			(start -0.7239 1.9939)
			(end -0.7239 -0.2159)
			(stroke
				(width 0.1)
				(type default)
			)
			(layer "B.Fab")
		)
		(fp_line
			(start -0.7239 -0.2159)
			(end 0.7239 -0.2159)
			(stroke
				(width 0.1)
				(type default)
			)
			(layer "B.Fab")
		)
		(pad "1" smd rect
			(at 0 0)
			(size 1.27 1.016)
			(layers "B.Cu" "B.Mask" "B.Paste")
			(net "PVCCIN_CPU0")
		)
		(pad "2" smd rect
			(at 0 1.778)
			(size 1.27 1.016)
			(layers "B.Cu" "B.Mask" "B.Paste")
			(net "GND")
		)
		(zone
			(layer "B.Cu")
			(hatch none 0.5)
			(connect_pads
				(clearance 0)
			)
			(min_thickness 0.25)
			(keepout
				(tracks not_allowed)
				(vias allowed)
				(pads allowed)
				(copperpour not_allowed)
				(footprints allowed)
			)
			(placement
				(enabled no)
				(sheetname "")
			)
			(fill
				(thermal_gap 0.5)
				(thermal_bridge_width 0.5)
				(island_removal_mode 0)
			)
			(polygon
				(pts
					(xy 263.781286 -80.11414) (xy 265.051286 -80.11414) (xy 265.051286 -80.87614) (xy 263.781286 -80.87614)
				)
			)
		)
	)
	(footprint ""
		(layer "B.Cu")
		(at 476.234506 -27.703018 180)
		(property "Reference" "C2T17"
			(at 0 0 0)
			(layer "B.SilkS")
			(hide yes)
			(effects
				(font
					(size 1.27 1.27)
				)
				(justify mirror)
			)
		)
		(property "Value" ""
			(at 0 0 0)
			(layer "B.Fab")
			(effects
				(font
					(size 1.27 1.27)
				)
				(justify mirror)
			)
		)
		(duplicate_pad_numbers_are_jumpers no)
		(fp_poly
			(pts
				(xy -0.3048 -0.1016) (xy -0.3048 0.9906) (xy 0.3048 0.9906) (xy 0.3048 -0.1016)
			)
			(stroke
				(width 0)
				(type default)
			)
			(fill no)
			(layer "B.CrtYd")
		)
		(fp_line
			(start 0.3048 0.9906)
			(end -0.3048 0.9906)
			(stroke
				(width 0.1)
				(type default)
			)
			(layer "B.Fab")
		)
		(fp_line
			(start 0.3048 -0.1016)
			(end 0.3048 0.9906)
			(stroke
				(width 0.1)
				(type default)
			)
			(layer "B.Fab")
		)
		(fp_line
			(start -0.3048 0.9906)
			(end -0.3048 -0.1016)
			(stroke
				(width 0.1)
				(type default)
			)
			(layer "B.Fab")
		)
		(fp_line
			(start -0.3048 -0.1016)
			(end 0.3048 -0.1016)
			(stroke
				(width 0.1)
				(type default)
			)
			(layer "B.Fab")
		)
		(pad "1" smd rect
			(at 0 0)
			(size 0.508 0.508)
			(layers "B.Cu" "B.Mask" "B.Paste")
			(net "P3V3_STBY_MNG")
		)
		(pad "2" smd rect
			(at 0 0.889)
			(size 0.508 0.508)
			(layers "B.Cu" "B.Mask" "B.Paste")
			(net "GND")
		)
		(zone
			(layer "B.Cu")
			(hatch none 0.5)
			(connect_pads
				(clearance 0)
			)
			(min_thickness 0.25)
			(keepout
				(tracks not_allowed)
				(vias allowed)
				(pads allowed)
				(copperpour not_allowed)
				(footprints allowed)
			)
			(placement
				(enabled no)
				(sheetname "")
			)
			(fill
				(thermal_gap 0.5)
				(thermal_bridge_width 0.5)
				(island_removal_mode 0)
			)
			(polygon
				(pts
					(xy 475.980506 -28.338018) (xy 476.488506 -28.338018) (xy 476.488506 -27.957018) (xy 475.980506 -27.957018)
				)
			)
		)
		(zone
			(layer "B.Cu")
			(hatch none 0.5)
			(connect_pads
				(clearance 0)
			)
			(min_thickness 0.25)
			(keepout
				(tracks allowed)
				(vias not_allowed)
				(pads allowed)
				(copperpour not_allowed)
				(footprints allowed)
			)
			(placement
				(enabled no)
				(sheetname "")
			)
			(fill
				(thermal_gap 0.5)
				(thermal_bridge_width 0.5)
				(island_removal_mode 0)
			)
			(polygon
				(pts
					(xy 475.980506 -27.957018) (xy 476.488506 -27.957018) (xy 476.488506 -28.338018) (xy 475.980506 -28.338018)
				)
			)
		)
	)
	(footprint ""
		(layer "B.Cu")
		(at 397.637 -88.2142)
		(property "Reference" "R8D4"
			(at 0 0 0)
			(layer "B.SilkS")
			(hide yes)
			(effects
				(font
					(size 1.27 1.27)
				)
				(justify mirror)
			)
		)
		(property "Value" ""
			(at 0 0 0)
			(layer "B.Fab")
			(effects
				(font
					(size 1.27 1.27)
				)
				(justify mirror)
			)
		)
		(duplicate_pad_numbers_are_jumpers no)
		(fp_poly
			(pts
				(xy 0.2794 -0.1016) (xy -0.2794 -0.1016) (xy -0.2794 0.9906) (xy 0.2794 0.9906)
			)
			(stroke
				(width 0)
				(type default)
			)
			(fill no)
			(layer "B.CrtYd")
		)
		(fp_line
			(start -0.2794 -0.1016)
			(end 0.2794 -0.1016)
			(stroke
				(width 0.1)
				(type default)
			)
			(layer "B.Fab")
		)
		(fp_line
			(start -0.2794 0.9906)
			(end -0.2794 -0.1016)
			(stroke
				(width 0.1)
				(type default)
			)
			(layer "B.Fab")
		)
		(fp_line
			(start 0.2794 -0.1016)
			(end 0.2794 0.9906)
			(stroke
				(width 0.1)
				(type default)
			)
			(layer "B.Fab")
		)
		(fp_line
			(start 0.2794 0.9906)
			(end -0.2794 0.9906)
			(stroke
				(width 0.1)
				(type default)
			)
			(layer "B.Fab")
		)
		(pad "1" smd rect
			(at 0 0 180)
			(size 0.508 0.508)
			(layers "B.Cu" "B.Mask" "B.Paste")
			(net "SMB_VR_STBY_LVC3_SCL_R1")
		)
		(pad "2" smd rect
			(at 0 0.889 180)
			(size 0.508 0.508)
			(layers "B.Cu" "B.Mask" "B.Paste")
			(net "SMB_VR_STBY_LVC3_SCL")
		)
		(zone
			(layer "B.Cu")
			(hatch none 0.5)
			(connect_pads
				(clearance 0)
			)
			(min_thickness 0.25)
			(keepout
				(tracks allowed)
				(vias not_allowed)
				(pads allowed)
				(copperpour not_allowed)
				(footprints allowed)
			)
			(placement
				(enabled no)
				(sheetname "")
			)
			(fill
				(thermal_gap 0.5)
				(thermal_bridge_width 0.5)
				(island_removal_mode 0)
			)
			(polygon
				(pts
					(xy 397.891 -87.9602) (xy 397.383 -87.9602) (xy 397.383 -87.5792) (xy 397.891 -87.5792)
				)
			)
		)
		(zone
			(layer "B.Cu")
			(hatch none 0.5)
			(connect_pads
				(clearance 0)
			)
			(min_thickness 0.25)
			(keepout
				(tracks not_allowed)
				(vias allowed)
				(pads allowed)
				(copperpour not_allowed)
				(footprints allowed)
			)
			(placement
				(enabled no)
				(sheetname "")
			)
			(fill
				(thermal_gap 0.5)
				(thermal_bridge_width 0.5)
				(island_removal_mode 0)
			)
			(polygon
				(pts
					(xy 397.891 -87.5792) (xy 397.383 -87.5792) (xy 397.383 -87.9602) (xy 397.891 -87.9602)
				)
			)
		)
	)
	(footprint ""
		(layer "B.Cu")
		(at 32.832802 -90.809064 90)
		(property "Reference" "C9N26"
			(at 0 0 90)
			(layer "B.SilkS")
			(hide yes)
			(effects
				(font
					(size 1.27 1.27)
				)
				(justify mirror)
			)
		)
		(property "Value" ""
			(at 0 0 90)
			(layer "B.Fab")
			(effects
				(font
					(size 1.27 1.27)
				)
				(justify mirror)
			)
		)
		(duplicate_pad_numbers_are_jumpers no)
		(fp_poly
			(pts
				(xy 0.7239 -0.2159) (xy -0.7239 -0.2159) (xy -0.7239 1.9939) (xy 0.7239 1.9939)
			)
			(stroke
				(width 0)
				(type default)
			)
			(fill no)
			(layer "B.CrtYd")
		)
		(fp_line
			(start 0.7239 -0.2159)
			(end 0.7239 1.9939)
			(stroke
				(width 0.1)
				(type default)
			)
			(layer "B.Fab")
		)
		(fp_line
			(start -0.7239 -0.2159)
			(end 0.7239 -0.2159)
			(stroke
				(width 0.1)
				(type default)
			)
			(layer "B.Fab")
		)
		(fp_line
			(start 0.7239 1.9939)
			(end -0.7239 1.9939)
			(stroke
				(width 0.1)
				(type default)
			)
			(layer "B.Fab")
		)
		(fp_line
			(start -0.7239 1.9939)
			(end -0.7239 -0.2159)
			(stroke
				(width 0.1)
				(type default)
			)
			(layer "B.Fab")
		)
		(pad "1" smd rect
			(at 0 0 270)
			(size 1.27 1.016)
			(layers "B.Cu" "B.Mask" "B.Paste")
			(net "VR_FET_SW_P12V_STBY_PVCCIN_CPU1")
		)
		(pad "2" smd rect
			(at 0 1.778 270)
			(size 1.27 1.016)
			(layers "B.Cu" "B.Mask" "B.Paste")
			(net "GND")
		)
		(zone
			(layer "B.Cu")
			(hatch none 0.5)
			(connect_pads
				(clearance 0)
			)
			(min_thickness 0.25)
			(keepout
				(tracks not_allowed)
				(vias allowed)
				(pads allowed)
				(copperpour not_allowed)
				(footprints allowed)
			)
			(placement
				(enabled no)
				(sheetname "")
			)
			(fill
				(thermal_gap 0.5)
				(thermal_bridge_width 0.5)
				(island_removal_mode 0)
			)
			(polygon
				(pts
					(xy 33.340802 -91.444064) (xy 33.340802 -90.174064) (xy 34.102802 -90.174064) (xy 34.102802 -91.444064)
				)
			)
		)
	)
	(footprint ""
		(layer "B.Cu")
		(at 356.08768 -94.072202 90)
		(property "Reference" "C22W31"
			(at 0 0 90)
			(layer "B.SilkS")
			(hide yes)
			(effects
				(font
					(size 1.27 1.27)
				)
				(justify mirror)
			)
		)
		(property "Value" "*"
			(at 0.0762 -6.2357 90)
			(unlocked yes)
			(layer "B.Fab")
			(hide yes)
			(effects
				(font
					(size 1.27 1.016)
					(thickness 0.1524)
				)
				(justify mirror)
			)
		)
		(property "Device Type" "SC22U16V5MX-4-GP_SMD-BCG5-SC22A"
			(at 0.0762 -8.2677 90)
			(unlocked yes)
			(layer "B.Fab")
			(hide yes)
			(effects
				(font
					(size 1.27 1.016)
					(thickness 0.1524)
				)
				(justify mirror)
			)
		)
		(duplicate_pad_numbers_are_jumpers no)
		(fp_line
			(start -0.635 0)
			(end 0.635 0)
			(stroke
				(width 0.508)
				(type default)
			)
			(layer "B.SilkS")
		)
		(fp_rect
			(start 0.9652 1.778)
			(end -0.9652 -1.778)
			(stroke
				(width 0)
				(type default)
			)
			(fill no)
			(layer "B.CrtYd")
		)
		(fp_poly
			(pts
				(xy 0.9652 -1.778) (xy -0.9652 -1.778) (xy -0.9652 1.778) (xy 0.9652 1.778)
			)
			(stroke
				(width 0)
				(type default)
			)
			(fill no)
			(layer "B.Fab")
		)
		(pad "1" smd rect
			(at 0 -0.9652 270)
			(size 1.397 1.143)
			(layers "B.Cu" "B.Mask" "B.Paste")
			(net "VR_FET_SW_P12V_STBY_PVCCIO_CPU0")
		)
		(pad "2" smd rect
			(at 0 0.9652 270)
			(size 1.397 1.143)
			(layers "B.Cu" "B.Mask" "B.Paste")
			(net "GND")
		)
	)
	(footprint ""
		(layer "B.Cu")
		(at 351.2312 -85.1408 90)
		(property "Reference" "C3P7"
			(at 0 0 90)
			(layer "B.SilkS")
			(hide yes)
			(effects
				(font
					(size 1.27 1.27)
				)
				(justify mirror)
			)
		)
		(property "Value" ""
			(at 0 0 90)
			(layer "B.Fab")
			(effects
				(font
					(size 1.27 1.27)
				)
				(justify mirror)
			)
		)
		(duplicate_pad_numbers_are_jumpers no)
		(fp_poly
			(pts
				(xy -0.3048 -0.1016) (xy -0.3048 0.9906) (xy 0.3048 0.9906) (xy 0.3048 -0.1016)
			)
			(stroke
				(width 0)
				(type default)
			)
			(fill no)
			(layer "B.CrtYd")
		)
		(fp_line
			(start 0.3048 -0.1016)
			(end 0.3048 0.9906)
			(stroke
				(width 0.1)
				(type default)
			)
			(layer "B.Fab")
		)
		(fp_line
			(start -0.3048 -0.1016)
			(end 0.3048 -0.1016)
			(stroke
				(width 0.1)
				(type default)
			)
			(layer "B.Fab")
		)
		(fp_line
			(start 0.3048 0.9906)
			(end -0.3048 0.9906)
			(stroke
				(width 0.1)
				(type default)
			)
			(layer "B.Fab")
		)
		(fp_line
			(start -0.3048 0.9906)
			(end -0.3048 -0.1016)
			(stroke
				(width 0.1)
				(type default)
			)
			(layer "B.Fab")
		)
		(pad "1" smd rect
			(at 0 0 270)
			(size 0.508 0.508)
			(layers "B.Cu" "B.Mask" "B.Paste")
			(net "VR_PVCCIO_CPU0_VDD")
		)
		(pad "2" smd rect
			(at 0 0.889 270)
			(size 0.508 0.508)
			(layers "B.Cu" "B.Mask" "B.Paste")
			(net "GND")
		)
		(zone
			(layer "B.Cu")
			(hatch none 0.5)
			(connect_pads
				(clearance 0)
			)
			(min_thickness 0.25)
			(keepout
				(tracks allowed)
				(vias not_allowed)
				(pads allowed)
				(copperpour not_allowed)
				(footprints allowed)
			)
			(placement
				(enabled no)
				(sheetname "")
			)
			(fill
				(thermal_gap 0.5)
				(thermal_bridge_width 0.5)
				(island_removal_mode 0)
			)
			(polygon
				(pts
					(xy 351.4852 -85.3948) (xy 351.4852 -84.8868) (xy 351.8662 -84.8868) (xy 351.8662 -85.3948)
				)
			)
		)
		(zone
			(layer "B.Cu")
			(hatch none 0.5)
			(connect_pads
				(clearance 0)
			)
			(min_thickness 0.25)
			(keepout
				(tracks not_allowed)
				(vias allowed)
				(pads allowed)
				(copperpour not_allowed)
				(footprints allowed)
			)
			(placement
				(enabled no)
				(sheetname "")
			)
			(fill
				(thermal_gap 0.5)
				(thermal_bridge_width 0.5)
				(island_removal_mode 0)
			)
			(polygon
				(pts
					(xy 351.8662 -85.3948) (xy 351.8662 -84.8868) (xy 351.4852 -84.8868) (xy 351.4852 -85.3948)
				)
			)
		)
	)
)
